FILE_TYPE = MULTI_PHYS_TABLE;

PART '9ZXL0451EKILFT'

{========================================================================================}
:VALUE            | PART_TYPE | MATERIAL | PART_NUMBER    = STANDARD        | LIFECYCLE     | PART_NUMBER   | JEDEC_TYPE              | DESCRIPTION                            | MANUFTR | MANUF_PN         | RD_CMPLS_LVL | CMPLS_LVL | FROM_PJ    | CLASS | DIP_SMD | DATA                     | EE_CHECK_LIST | FP_ECN | PSL | CREATOR | STATUS | MSD  | ESD_CDM | ESD_HBM | ESD_MM | PIN_LENGTH_SHORT_PIN | PIN_LENGTH_LONG_PIN | CREATEDAY  ;
{========================================================================================}
 '9ZXL0451EKILFT' | 'SMLF'    | 'IC'     | 'AL000451003'(!) = ''               | ''               | 'AL000451003' |'VFQFPN32_TH_0-5_5X5XD'| 'IC OTHER(32P) 9ZXL0451EKILFT(VFQFPN)' | 'IDT'   | '9ZXL0451EKILFT' | 'EP(V1)'     | 'EP(V1)'  | 'S69-JEFF' | 'IC'  | ''      | 'IDT_9ZXL0451EKILFT.pdf' | ''            | ''     | ''  | ''      | ''     | 'NA' | 'NA'    | 'NA'    | 'NA'   | '0 MILS'             | '0 MILS'            | '20190416'
 '9ZXL0451EKILFT' | 'SMLF'    | 'EMPTY'  | 'AL000451003'(!) = ''               | ''               | 'AL000451003' |'VFQFPN32_TH_0-5_5X5XD'| 'IC OTHER(32P) 9ZXL0451EKILFT(VFQFPN)' | 'IDT'   | '9ZXL0451EKILFT' | 'EP(V1)'     | 'EP(V1)'  | 'S69-JEFF' | 'IC'  | ''      | 'IDT_9ZXL0451EKILFT.pdf' | ''            | ''     | ''  | ''      | ''     | 'NA' | 'NA'    | 'NA'    | 'NA'   | '0 MILS'             | '0 MILS'            | '20190416'

END_PART

END.

